(kicad_pcb
	(version 20260206)
	(generator "pcbnew")
	(generator_version "10.0")
	(general
		(thickness 1.6)
		(legacy_teardrops no)
	)
	(paper "A4")
	(title_block
		(title "03242023_DA0F0TMBIJ0_F0T_Motherboard_J_brd_V01_OCP.brd")
		(comment 1 "Grand Teton / footprints 1290-1293 of 6105")
	)
	(layers
		(0 "F.Cu" signal "TOP")
		(4 "In1.Cu" signal "GND")
		(6 "In2.Cu" signal "IN1")
		(8 "In3.Cu" signal "GND1")
		(10 "In4.Cu" signal "IN2")
		(12 "In5.Cu" signal "GND2")
		(14 "In6.Cu" signal "IN3")
		(16 "In7.Cu" signal "GND3")
		(18 "In8.Cu" signal "VCC")
		(20 "In9.Cu" signal "VCC1")
		(22 "In10.Cu" signal "GND4")
		(24 "In11.Cu" signal "IN4")
		(26 "In12.Cu" signal "GND5")
		(28 "In13.Cu" signal "IN5")
		(30 "In14.Cu" signal "GND6")
		(32 "In15.Cu" signal "IN6")
		(34 "In16.Cu" signal "GND7")
		(2 "B.Cu" signal "BOTTOM")
		(9 "F.Adhes" user "F.Adhesive")
		(11 "B.Adhes" user "B.Adhesive")
		(13 "F.Paste" user "Package Geometry/Pastemask Top")
		(15 "B.Paste" user "Package Geometry/Pastemask Bottom")
		(5 "F.SilkS" user "Ref Des/Silkscreen Top")
		(7 "B.SilkS" user "Ref Des/Silkscreen Bottom")
		(1 "F.Mask" user "Board Geometry/Soldermask Top")
		(3 "B.Mask" user "Board Geometry/Soldermask Bottom")
		(17 "Dwgs.User" user "User.Drawings")
		(19 "Cmts.User" user "User.Comments")
		(21 "Eco1.User" user "User.Eco1")
		(23 "Eco2.User" user "User.Eco2")
		(25 "Edge.Cuts" user "Board Geometry/Outline")
		(27 "Margin" user)
		(31 "F.CrtYd" user "Package Geometry/Place Bound Top")
		(29 "B.CrtYd" user "Package Geometry/Place Bound Bottom")
		(35 "F.Fab" user "Ref Des/Assembly Top")
		(33 "B.Fab" user "Ref Des/Assembly Bottom")
	)
	(footprint ""
		(layer "F.Cu")
		(at 106.476038 -37.940742)
		(property "Reference" "R3188"
			(at 0 0 0)
			(layer "F.SilkS")
			(hide yes)
			(effects
				(font
					(size 1.27 1.27)
				)
			)
		)
		(property "Value" ""
			(at 0 0 0)
			(layer "F.Fab")
			(effects
				(font
					(size 1.27 1.27)
				)
			)
		)
		(duplicate_pad_numbers_are_jumpers no)
		(fp_line
			(start -0.7874 -0.4064)
			(end 0.7874 -0.4064)
			(stroke
				(width 0.1524)
				(type default)
			)
			(layer "F.SilkS")
		)
		(fp_line
			(start -0.7874 0.4064)
			(end -0.7874 -0.4064)
			(stroke
				(width 0.1524)
				(type default)
			)
			(layer "F.SilkS")
		)
		(fp_line
			(start 0.7874 -0.4064)
			(end 0.7874 0.4064)
			(stroke
				(width 0.1524)
				(type default)
			)
			(layer "F.SilkS")
		)
		(fp_line
			(start 0.7874 0.4064)
			(end -0.7874 0.4064)
			(stroke
				(width 0.1524)
				(type default)
			)
			(layer "F.SilkS")
		)
		(fp_line
			(start -0.67945 -0.305054)
			(end -0.12065 -0.305054)
			(stroke
				(width 0.1)
				(type default)
			)
			(layer "F.Fab")
		)
		(fp_line
			(start -0.67945 0.3048)
			(end -0.67945 -0.305054)
			(stroke
				(width 0.1)
				(type default)
			)
			(layer "F.Fab")
		)
		(fp_line
			(start -0.12065 -0.305054)
			(end -0.12065 -0.2794)
			(stroke
				(width 0.1)
				(type default)
			)
			(layer "F.Fab")
		)
		(fp_line
			(start -0.12065 -0.2794)
			(end 0.12065 -0.2794)
			(stroke
				(width 0.1)
				(type default)
			)
			(layer "F.Fab")
		)
		(fp_line
			(start -0.12065 0.2794)
			(end -0.12065 0.3048)
			(stroke
				(width 0.1)
				(type default)
			)
			(layer "F.Fab")
		)
		(fp_line
			(start -0.12065 0.3048)
			(end -0.67945 0.3048)
			(stroke
				(width 0.1)
				(type default)
			)
			(layer "F.Fab")
		)
		(fp_line
			(start 0.120396 0.2794)
			(end -0.12065 0.2794)
			(stroke
				(width 0.1)
				(type default)
			)
			(layer "F.Fab")
		)
		(fp_line
			(start 0.120396 0.3048)
			(end 0.120396 0.2794)
			(stroke
				(width 0.1)
				(type default)
			)
			(layer "F.Fab")
		)
		(fp_line
			(start 0.12065 -0.3048)
			(end 0.67945 -0.3048)
			(stroke
				(width 0.1)
				(type default)
			)
			(layer "F.Fab")
		)
		(fp_line
			(start 0.12065 -0.2794)
			(end 0.12065 -0.3048)
			(stroke
				(width 0.1)
				(type default)
			)
			(layer "F.Fab")
		)
		(fp_line
			(start 0.67945 -0.3048)
			(end 0.67945 0.3048)
			(stroke
				(width 0.1)
				(type default)
			)
			(layer "F.Fab")
		)
		(fp_line
			(start 0.67945 0.3048)
			(end 0.120396 0.3048)
			(stroke
				(width 0.1)
				(type default)
			)
			(layer "F.Fab")
		)
		(pad "1" smd circle
			(at -0.40005 0)
			(size 0 0)
			(layers "F.Cu" "F.Mask" "F.Paste")
			(net "RST_OCP_V3_2_BUF_N")
		)
		(pad "2" smd circle
			(at 0.40005 0)
			(size 0 0)
			(layers "F.Cu" "F.Mask" "F.Paste")
			(net "RST_PERST2_OCP_V3_2_N")
		)
	)
	(footprint ""
		(layer "F.Cu")
		(at 106.11231 -65.22212 -90)
		(property "Reference" "R3090"
			(at 0 0 270)
			(layer "F.SilkS")
			(hide yes)
			(effects
				(font
					(size 1.27 1.27)
				)
			)
		)
		(property "Value" ""
			(at 0 0 270)
			(layer "F.Fab")
			(effects
				(font
					(size 1.27 1.27)
				)
			)
		)
		(duplicate_pad_numbers_are_jumpers no)
		(fp_line
			(start -0.7874 0.4064)
			(end -0.7874 -0.4064)
			(stroke
				(width 0.1524)
				(type default)
			)
			(layer "F.SilkS")
		)
		(fp_line
			(start 0.7874 0.4064)
			(end -0.7874 0.4064)
			(stroke
				(width 0.1524)
				(type default)
			)
			(layer "F.SilkS")
		)
		(fp_line
			(start -0.7874 -0.4064)
			(end 0.7874 -0.4064)
			(stroke
				(width 0.1524)
				(type default)
			)
			(layer "F.SilkS")
		)
		(fp_line
			(start 0.7874 -0.4064)
			(end 0.7874 0.4064)
			(stroke
				(width 0.1524)
				(type default)
			)
			(layer "F.SilkS")
		)
		(fp_line
			(start -0.67945 0.3048)
			(end -0.67945 -0.305054)
			(stroke
				(width 0.1)
				(type default)
			)
			(layer "F.Fab")
		)
		(fp_line
			(start -0.12065 0.3048)
			(end -0.67945 0.3048)
			(stroke
				(width 0.1)
				(type default)
			)
			(layer "F.Fab")
		)
		(fp_line
			(start 0.120396 0.3048)
			(end 0.120396 0.2794)
			(stroke
				(width 0.1)
				(type default)
			)
			(layer "F.Fab")
		)
		(fp_line
			(start 0.67945 0.3048)
			(end 0.120396 0.3048)
			(stroke
				(width 0.1)
				(type default)
			)
			(layer "F.Fab")
		)
		(fp_line
			(start -0.12065 0.2794)
			(end -0.12065 0.3048)
			(stroke
				(width 0.1)
				(type default)
			)
			(layer "F.Fab")
		)
		(fp_line
			(start 0.120396 0.2794)
			(end -0.12065 0.2794)
			(stroke
				(width 0.1)
				(type default)
			)
			(layer "F.Fab")
		)
		(fp_line
			(start -0.12065 -0.2794)
			(end 0.12065 -0.2794)
			(stroke
				(width 0.1)
				(type default)
			)
			(layer "F.Fab")
		)
		(fp_line
			(start 0.12065 -0.2794)
			(end 0.12065 -0.3048)
			(stroke
				(width 0.1)
				(type default)
			)
			(layer "F.Fab")
		)
		(fp_line
			(start 0.12065 -0.3048)
			(end 0.67945 -0.3048)
			(stroke
				(width 0.1)
				(type default)
			)
			(layer "F.Fab")
		)
		(fp_line
			(start 0.67945 -0.3048)
			(end 0.67945 0.3048)
			(stroke
				(width 0.1)
				(type default)
			)
			(layer "F.Fab")
		)
		(fp_line
			(start -0.67945 -0.305054)
			(end -0.12065 -0.305054)
			(stroke
				(width 0.1)
				(type default)
			)
			(layer "F.Fab")
		)
		(fp_line
			(start -0.12065 -0.305054)
			(end -0.12065 -0.2794)
			(stroke
				(width 0.1)
				(type default)
			)
			(layer "F.Fab")
		)
		(pad "1" smd circle
			(at -0.40005 0 270)
			(size 0 0)
			(layers "F.Cu" "F.Mask" "F.Paste")
			(net "LED_PWRGD_PVNN_MAIN_CPU0")
		)
		(pad "2" smd circle
			(at 0.40005 0 270)
			(size 0 0)
			(layers "F.Cu" "F.Mask" "F.Paste")
			(net "P3V3_AUX")
		)
	)
	(footprint ""
		(layer "F.Cu")
		(at 440.687968 -94.077536 180)
		(property "Reference" "U266"
			(at 0.221996 2.912872 0)
			(unlocked yes)
			(layer "F.SilkS")
			(effects
				(font
					(size 0.7874 0.5842)
					(thickness 0.1524)
				)
			)
		)
		(property "Value" ""
			(at 0 0 180)
			(layer "F.Fab")
			(effects
				(font
					(size 1.27 1.27)
				)
			)
		)
		(duplicate_pad_numbers_are_jumpers no)
		(fp_line
			(start 1.500124 1.500124)
			(end 1.004062 1.500124)
			(stroke
				(width 0.1524)
				(type default)
			)
			(layer "F.SilkS")
		)
		(fp_line
			(start 1.500124 1.004062)
			(end 1.500124 1.500124)
			(stroke
				(width 0.1524)
				(type default)
			)
			(layer "F.SilkS")
		)
		(fp_line
			(start 1.500124 -1.500124)
			(end 1.500124 -1.004062)
			(stroke
				(width 0.1524)
				(type default)
			)
			(layer "F.SilkS")
		)
		(fp_line
			(start 1.004062 -1.500124)
			(end 1.500124 -1.500124)
			(stroke
				(width 0.1524)
				(type default)
			)
			(layer "F.SilkS")
		)
		(fp_line
			(start -1.004062 1.500124)
			(end -1.500124 1.500124)
			(stroke
				(width 0.1524)
				(type default)
			)
			(layer "F.SilkS")
		)
		(fp_line
			(start -1.500124 1.500124)
			(end -1.500124 1.004062)
			(stroke
				(width 0.1524)
				(type default)
			)
			(layer "F.SilkS")
		)
		(fp_line
			(start -1.500124 -1.004062)
			(end -1.500124 -1.500124)
			(stroke
				(width 0.1524)
				(type default)
			)
			(layer "F.SilkS")
		)
		(fp_line
			(start -1.500124 -1.500124)
			(end -1.004062 -1.500124)
			(stroke
				(width 0.1524)
				(type default)
			)
			(layer "F.SilkS")
		)
		(fp_poly
			(pts
				(xy -2.242312 -0.999744) (xy -1.783588 -0.770382) (xy -2.242312 -0.54102)
			)
			(stroke
				(width 0)
				(type default)
			)
			(fill yes)
			(layer "F.SilkS")
		)
		(fp_line
			(start 1.500124 1.500124)
			(end -1.500124 1.500124)
			(stroke
				(width 0.1)
				(type default)
			)
			(layer "F.Fab")
		)
		(fp_line
			(start 1.500124 -1.500124)
			(end 1.500124 1.500124)
			(stroke
				(width 0.1)
				(type default)
			)
			(layer "F.Fab")
		)
		(fp_line
			(start -1.500124 1.500124)
			(end -1.500124 -1.500124)
			(stroke
				(width 0.1)
				(type default)
			)
			(layer "F.Fab")
		)
		(fp_line
			(start -1.500124 -1.500124)
			(end 1.500124 -1.500124)
			(stroke
				(width 0.1)
				(type default)
			)
			(layer "F.Fab")
		)
		(fp_poly
			(pts
				(xy -2.847848 -1.258062) (xy -2.847848 -0.242062) (xy -1.831848 -0.750062)
			)
			(stroke
				(width 0)
				(type default)
			)
			(fill yes)
			(layer "F.Fab")
		)
		(pad "1" smd rect
			(at -1.400048 -0.750062 90)
			(size 0.2286 0.6096)
			(layers "F.Cu" "F.Mask" "F.Paste")
			(net "INA230_1_A1")
		)
		(pad "2" smd rect
			(at -1.400048 -0.249936 90)
			(size 0.2286 0.6096)
			(layers "F.Cu" "F.Mask" "F.Paste")
			(net "INA230_1_A0")
		)
		(pad "3" smd rect
			(at -1.400048 0.249936 90)
			(size 0.2286 0.6096)
			(layers "F.Cu" "F.Mask" "F.Paste")
			(net "OCP_SFF_P3V3_ADC_ALERT_R")
		)
		(pad "4" smd rect
			(at -1.400048 0.750062 90)
			(size 0.2286 0.6096)
			(layers "F.Cu" "F.Mask" "F.Paste")
			(net "SMB_INA230_1_3V3AUX_SDA_R1")
		)
		(pad "5" smd rect
			(at -0.750062 1.400048 180)
			(size 0.2286 0.6096)
			(layers "F.Cu" "F.Mask" "F.Paste")
			(net "SMB_INA230_1_3V3AUX_SCL_R1")
		)
		(pad "6" smd rect
			(at -0.249936 1.400048 180)
			(size 0.2286 0.6096)
			(layers "F.Cu" "F.Mask" "F.Paste")
			(net "NC_INA230_1_NC0")
		)
		(pad "7" smd rect
			(at 0.249936 1.400048 180)
			(size 0.2286 0.6096)
			(layers "F.Cu" "F.Mask" "F.Paste")
			(net "NC_INA230_1_NC1")
		)
		(pad "8" smd rect
			(at 0.750062 1.400048 180)
			(size 0.2286 0.6096)
			(layers "F.Cu" "F.Mask" "F.Paste")
			(net "NC_INA230_1_NC2")
		)
		(pad "9" smd rect
			(at 1.400048 0.750062 90)
			(size 0.2286 0.6096)
			(layers "F.Cu" "F.Mask" "F.Paste")
			(net "P3V3_AUX")
		)
		(pad "10" smd rect
			(at 1.400048 0.249936 90)
			(size 0.2286 0.6096)
			(layers "F.Cu" "F.Mask" "F.Paste")
			(net "GND")
		)
		(pad "11" smd rect
			(at 1.400048 -0.249936 90)
			(size 0.2286 0.6096)
			(layers "F.Cu" "F.Mask" "F.Paste")
			(net "P3V3_OCP_SFF_R")
		)
		(pad "12" smd rect
			(at 1.400048 -0.750062 90)
			(size 0.2286 0.6096)
			(layers "F.Cu" "F.Mask" "F.Paste")
			(net "VSENSE_P3V3_INA230_1_INN")
		)
		(pad "13" smd rect
			(at 0.750062 -1.400048 180)
			(size 0.2286 0.6096)
			(layers "F.Cu" "F.Mask" "F.Paste")
			(net "VSENSE_P3V3_INA230_1_INP")
		)
		(pad "14" smd rect
			(at 0.249936 -1.400048 180)
			(size 0.2286 0.6096)
			(layers "F.Cu" "F.Mask" "F.Paste")
			(net "NC_INA230_1_NC3")
		)
		(pad "15" smd rect
			(at -0.249936 -1.400048 180)
			(size 0.2286 0.6096)
			(layers "F.Cu" "F.Mask" "F.Paste")
			(net "NC_INA230_1_NC4")
		)
		(pad "16" smd rect
			(at -0.750062 -1.400048 180)
			(size 0.2286 0.6096)
			(layers "F.Cu" "F.Mask" "F.Paste")
			(net "NC_INA230_1_NC5")
		)
		(pad "TH" smd rect
			(at 0 0 180)
			(size 1.7018 1.7018)
			(layers "F.Cu" "F.Mask" "F.Paste")
			(net "GND")
		)
		(zone
			(layer "F.Cu")
			(hatch none 0.5)
			(connect_pads
				(clearance 0)
			)
			(min_thickness 0.25)
			(keepout
				(tracks not_allowed)
				(vias allowed)
				(pads allowed)
				(copperpour not_allowed)
				(footprints allowed)
			)
			(placement
				(enabled no)
				(sheetname "")
			)
			(fill
				(thermal_gap 0.5)
				(thermal_bridge_width 0.5)
				(island_removal_mode 0)
			)
			(polygon
				(pts
					(xy 441.732416 -94.052136) (xy 441.732416 -93.033088) (xy 439.64352 -93.033088) (xy 439.64352 -95.121984)
					(xy 441.732416 -95.121984) (xy 441.732416 -94.077536) (xy 441.589668 -94.077536) (xy 441.589668 -94.979236)
					(xy 439.786268 -94.979236) (xy 439.786268 -93.175836) (xy 441.589668 -93.175836) (xy 441.589668 -94.052136)
				)
			)
		)
	)
	(footprint ""
		(layer "F.Cu")
		(at 366.48263 -255.053846 90)
		(property "Reference" "C1008"
			(at 0 0 90)
			(layer "F.SilkS")
			(hide yes)
			(effects
				(font
					(size 1.27 1.27)
				)
			)
		)
		(property "Value" ""
			(at 0 0 90)
			(layer "F.Fab")
			(effects
				(font
					(size 1.27 1.27)
				)
			)
		)
		(duplicate_pad_numbers_are_jumpers no)
		(fp_line
			(start 0.7874 -0.4064)
			(end 0.7874 0.4064)
			(stroke
				(width 0.1524)
				(type default)
			)
			(layer "F.SilkS")
		)
		(fp_line
			(start -0.7874 -0.4064)
			(end 0.7874 -0.4064)
			(stroke
				(width 0.1524)
				(type default)
			)
			(layer "F.SilkS")
		)
		(fp_line
			(start 0.7874 0.4064)
			(end -0.7874 0.4064)
			(stroke
				(width 0.1524)
				(type default)
			)
			(layer "F.SilkS")
		)
		(fp_line
			(start -0.7874 0.4064)
			(end -0.7874 -0.4064)
			(stroke
				(width 0.1524)
				(type default)
			)
			(layer "F.SilkS")
		)
		(fp_line
			(start -0.12065 -0.305054)
			(end -0.12065 -0.2794)
			(stroke
				(width 0.1)
				(type default)
			)
			(layer "F.Fab")
		)
		(fp_line
			(start -0.67945 -0.305054)
			(end -0.12065 -0.305054)
			(stroke
				(width 0.1)
				(type default)
			)
			(layer "F.Fab")
		)
		(fp_line
			(start 0.67945 -0.3048)
			(end 0.67945 0.3048)
			(stroke
				(width 0.1)
				(type default)
			)
			(layer "F.Fab")
		)
		(fp_line
			(start 0.12065 -0.3048)
			(end 0.67945 -0.3048)
			(stroke
				(width 0.1)
				(type default)
			)
			(layer "F.Fab")
		)
		(fp_line
			(start 0.12065 -0.2794)
			(end 0.12065 -0.3048)
			(stroke
				(width 0.1)
				(type default)
			)
			(layer "F.Fab")
		)
		(fp_line
			(start -0.12065 -0.2794)
			(end 0.12065 -0.2794)
			(stroke
				(width 0.1)
				(type default)
			)
			(layer "F.Fab")
		)
		(fp_line
			(start 0.120396 0.2794)
			(end -0.12065 0.2794)
			(stroke
				(width 0.1)
				(type default)
			)
			(layer "F.Fab")
		)
		(fp_line
			(start -0.12065 0.2794)
			(end -0.12065 0.3048)
			(stroke
				(width 0.1)
				(type default)
			)
			(layer "F.Fab")
		)
		(fp_line
			(start 0.67945 0.3048)
			(end 0.120396 0.3048)
			(stroke
				(width 0.1)
				(type default)
			)
			(layer "F.Fab")
		)
		(fp_line
			(start 0.120396 0.3048)
			(end 0.120396 0.2794)
			(stroke
				(width 0.1)
				(type default)
			)
			(layer "F.Fab")
		)
		(fp_line
			(start -0.12065 0.3048)
			(end -0.67945 0.3048)
			(stroke
				(width 0.1)
				(type default)
			)
			(layer "F.Fab")
		)
		(fp_line
			(start -0.67945 0.3048)
			(end -0.67945 -0.305054)
			(stroke
				(width 0.1)
				(type default)
			)
			(layer "F.Fab")
		)
		(pad "1" smd circle
			(at -0.40005 0 90)
			(size 0 0)
			(layers "F.Cu" "F.Mask" "F.Paste")
			(net "PVCCIN_CPU0")
		)
		(pad "2" smd circle
			(at 0.40005 0 90)
			(size 0 0)
			(layers "F.Cu" "F.Mask" "F.Paste")
			(net "GND")
		)
	)
)
